# T6G (Grand Teton) — schematic netlist excerpt (pin names and nets, part order shuffled) for the footprints in the layout excerpt that follows; sources: Cadence DE-HDL packaged netlist, KiCad conversion of 04192023_DAF0TMB3IC0_F0TG_MB_C_brd_V02_OCP.brd

R1058  Q_RES  20K 1% CHIP  pkg 0201LF  page 298 : A = RT_CPU0_P2_ADDR2 ; B = GND
R4171  Q_RES  33.2 1% CHIP  pkg 0402LF  page 81 : A = GPU_3V3IO_RSVD3_ISO_R ; B = GPU_3V3IO_RSVD3_ISO
PR90  Q_RES  5.6 1% CHIP  pkg 0402LF  page 202 : A = SW_PVDDCR_CPU1_P0_BOOT3 ; B = SW_PVDDCR_CPU1_P0_BOOT3_R

(kicad_pcb
	(version 20260206)
	(generator "pcbnew")
	(generator_version "10.0")
	(general
		(thickness 1.6)
		(legacy_teardrops no)
	)
	(paper "A4")
	(title_block
		(title "04192023_DAF0TMB3IC0_F0TG_MB_C_brd_V02_OCP.brd")
		(comment 1 "Grand Teton / footprints 2148-2150 of 8354")
	)
	(layers
		(0 "F.Cu" signal "TOP")
		(4 "In1.Cu" signal "GND")
		(6 "In2.Cu" signal "IN1")
		(8 "In3.Cu" signal "GND1")
		(10 "In4.Cu" signal "IN2")
		(12 "In5.Cu" signal "GND2")
		(14 "In6.Cu" signal "IN3")
		(16 "In7.Cu" signal "GND3")
		(18 "In8.Cu" signal "VCC")
		(20 "In9.Cu" signal "VCC1")
		(22 "In10.Cu" signal "GND4")
		(24 "In11.Cu" signal "IN4")
		(26 "In12.Cu" signal "GND5")
		(28 "In13.Cu" signal "IN5")
		(30 "In14.Cu" signal "GND6")
		(32 "In15.Cu" signal "IN6")
		(34 "In16.Cu" signal "GND7")
		(2 "B.Cu" signal "BOTTOM")
		(9 "F.Adhes" user "F.Adhesive")
		(11 "B.Adhes" user "B.Adhesive")
		(13 "F.Paste" user "Package Geometry/Pastemask Top")
		(15 "B.Paste" user "Package Geometry/Pastemask Bottom")
		(5 "F.SilkS" user "Ref Des/Silkscreen Top")
		(7 "B.SilkS" user "Ref Des/Silkscreen Bottom")
		(1 "F.Mask" user "Board Geometry/Soldermask Top")
		(3 "B.Mask" user "Board Geometry/Soldermask Bottom")
		(17 "Dwgs.User" user "User.Drawings")
		(19 "Cmts.User" user "User.Comments")
		(21 "Eco1.User" user "User.Eco1")
		(23 "Eco2.User" user "User.Eco2")
		(25 "Edge.Cuts" user "Board Geometry/Outline")
		(27 "Margin" user)
		(31 "F.CrtYd" user "Package Geometry/Place Bound Top")
		(29 "B.CrtYd" user "Package Geometry/Place Bound Bottom")
		(35 "F.Fab" user "Ref Des/Assembly Top")
		(33 "B.Fab" user "Ref Des/Assembly Bottom")
	)
	(footprint ""
		(layer "F.Cu")
		(at 319.105026 -339.647022 90)
		(property "Reference" "PR90"
			(at 0 0 90)
			(layer "F.SilkS")
			(hide yes)
			(effects
				(font
					(size 1.27 1.27)
				)
			)
		)
		(property "Value" ""
			(at 0 0 90)
			(layer "F.Fab")
			(effects
				(font
					(size 1.27 1.27)
				)
			)
		)
		(duplicate_pad_numbers_are_jumpers no)
		(fp_line
			(start 0.7874 -0.4064)
			(end 0.7874 0.4064)
			(stroke
				(width 0.1524)
				(type default)
			)
			(layer "F.SilkS")
		)
		(fp_line
			(start -0.7874 -0.4064)
			(end 0.7874 -0.4064)
			(stroke
				(width 0.1524)
				(type default)
			)
			(layer "F.SilkS")
		)
		(fp_line
			(start 0.7874 0.4064)
			(end -0.7874 0.4064)
			(stroke
				(width 0.1524)
				(type default)
			)
			(layer "F.SilkS")
		)
		(fp_line
			(start -0.7874 0.4064)
			(end -0.7874 -0.4064)
			(stroke
				(width 0.1524)
				(type default)
			)
			(layer "F.SilkS")
		)
		(fp_line
			(start -0.12065 -0.305054)
			(end -0.12065 -0.2794)
			(stroke
				(width 0.1)
				(type default)
			)
			(layer "F.Fab")
		)
		(fp_line
			(start -0.67945 -0.305054)
			(end -0.12065 -0.305054)
			(stroke
				(width 0.1)
				(type default)
			)
			(layer "F.Fab")
		)
		(fp_line
			(start 0.67945 -0.3048)
			(end 0.67945 0.3048)
			(stroke
				(width 0.1)
				(type default)
			)
			(layer "F.Fab")
		)
		(fp_line
			(start 0.12065 -0.3048)
			(end 0.67945 -0.3048)
			(stroke
				(width 0.1)
				(type default)
			)
			(layer "F.Fab")
		)
		(fp_line
			(start 0.12065 -0.2794)
			(end 0.12065 -0.3048)
			(stroke
				(width 0.1)
				(type default)
			)
			(layer "F.Fab")
		)
		(fp_line
			(start -0.12065 -0.2794)
			(end 0.12065 -0.2794)
			(stroke
				(width 0.1)
				(type default)
			)
			(layer "F.Fab")
		)
		(fp_line
			(start 0.120396 0.2794)
			(end -0.12065 0.2794)
			(stroke
				(width 0.1)
				(type default)
			)
			(layer "F.Fab")
		)
		(fp_line
			(start -0.12065 0.2794)
			(end -0.12065 0.3048)
			(stroke
				(width 0.1)
				(type default)
			)
			(layer "F.Fab")
		)
		(fp_line
			(start 0.67945 0.3048)
			(end 0.120396 0.3048)
			(stroke
				(width 0.1)
				(type default)
			)
			(layer "F.Fab")
		)
		(fp_line
			(start 0.120396 0.3048)
			(end 0.120396 0.2794)
			(stroke
				(width 0.1)
				(type default)
			)
			(layer "F.Fab")
		)
		(fp_line
			(start -0.12065 0.3048)
			(end -0.67945 0.3048)
			(stroke
				(width 0.1)
				(type default)
			)
			(layer "F.Fab")
		)
		(fp_line
			(start -0.67945 0.3048)
			(end -0.67945 -0.305054)
			(stroke
				(width 0.1)
				(type default)
			)
			(layer "F.Fab")
		)
		(pad "1" smd circle
			(at -0.40005 0 90)
			(size 0 0)
			(layers "F.Cu" "F.Mask" "F.Paste")
			(net "SW_PVDDCR_CPU1_P0_BOOT3")
		)
		(pad "2" smd circle
			(at 0.40005 0 90)
			(size 0 0)
			(layers "F.Cu" "F.Mask" "F.Paste")
			(net "SW_PVDDCR_CPU1_P0_BOOT3_R")
		)
	)
	(footprint ""
		(layer "F.Cu")
		(at 430.02835 -399.72488 180)
		(property "Reference" "R1058"
			(at 0 0 180)
			(layer "F.SilkS")
			(hide yes)
			(effects
				(font
					(size 1.27 1.27)
				)
			)
		)
		(property "Value" ""
			(at 0 0 180)
			(layer "F.Fab")
			(effects
				(font
					(size 1.27 1.27)
				)
			)
		)
		(duplicate_pad_numbers_are_jumpers no)
		(fp_line
			(start 0.32512 0.175006)
			(end -0.32512 0.175006)
			(stroke
				(width 0.1)
				(type default)
			)
			(layer "F.Fab")
		)
		(fp_line
			(start 0.32512 -0.175006)
			(end 0.32512 0.175006)
			(stroke
				(width 0.1)
				(type default)
			)
			(layer "F.Fab")
		)
		(fp_line
			(start -0.32512 0.175006)
			(end -0.32512 -0.175006)
			(stroke
				(width 0.1)
				(type default)
			)
			(layer "F.Fab")
		)
		(fp_line
			(start -0.32512 -0.175006)
			(end 0.32512 -0.175006)
			(stroke
				(width 0.1)
				(type default)
			)
			(layer "F.Fab")
		)
		(pad "1" smd rect
			(at -0.2667 0 180)
			(size 0.3048 0.381)
			(layers "F.Cu" "F.Mask" "F.Paste")
			(net "RT_CPU0_P2_ADDR2")
		)
		(pad "2" smd rect
			(at 0.2667 0)
			(size 0.3048 0.381)
			(layers "F.Cu" "F.Mask" "F.Paste")
			(net "GND")
		)
	)
	(footprint ""
		(layer "F.Cu")
		(at 197.269608 -115.657376)
		(property "Reference" "R4171"
			(at 0 0 0)
			(layer "F.SilkS")
			(hide yes)
			(effects
				(font
					(size 1.27 1.27)
				)
			)
		)
		(property "Value" ""
			(at 0 0 0)
			(layer "F.Fab")
			(effects
				(font
					(size 1.27 1.27)
				)
			)
		)
		(duplicate_pad_numbers_are_jumpers no)
		(fp_line
			(start -0.7874 -0.4064)
			(end 0.7874 -0.4064)
			(stroke
				(width 0.1524)
				(type default)
			)
			(layer "F.SilkS")
		)
		(fp_line
			(start -0.7874 0.4064)
			(end -0.7874 -0.4064)
			(stroke
				(width 0.1524)
				(type default)
			)
			(layer "F.SilkS")
		)
		(fp_line
			(start 0.7874 -0.4064)
			(end 0.7874 0.4064)
			(stroke
				(width 0.1524)
				(type default)
			)
			(layer "F.SilkS")
		)
		(fp_line
			(start 0.7874 0.4064)
			(end -0.7874 0.4064)
			(stroke
				(width 0.1524)
				(type default)
			)
			(layer "F.SilkS")
		)
		(fp_line
			(start -0.67945 -0.305054)
			(end -0.12065 -0.305054)
			(stroke
				(width 0.1)
				(type default)
			)
			(layer "F.Fab")
		)
		(fp_line
			(start -0.67945 0.3048)
			(end -0.67945 -0.305054)
			(stroke
				(width 0.1)
				(type default)
			)
			(layer "F.Fab")
		)
		(fp_line
			(start -0.12065 -0.305054)
			(end -0.12065 -0.2794)
			(stroke
				(width 0.1)
				(type default)
			)
			(layer "F.Fab")
		)
		(fp_line
			(start -0.12065 -0.2794)
			(end 0.12065 -0.2794)
			(stroke
				(width 0.1)
				(type default)
			)
			(layer "F.Fab")
		)
		(fp_line
			(start -0.12065 0.2794)
			(end -0.12065 0.3048)
			(stroke
				(width 0.1)
				(type default)
			)
			(layer "F.Fab")
		)
		(fp_line
			(start -0.12065 0.3048)
			(end -0.67945 0.3048)
			(stroke
				(width 0.1)
				(type default)
			)
			(layer "F.Fab")
		)
		(fp_line
			(start 0.120396 0.2794)
			(end -0.12065 0.2794)
			(stroke
				(width 0.1)
				(type default)
			)
			(layer "F.Fab")
		)
		(fp_line
			(start 0.120396 0.3048)
			(end 0.120396 0.2794)
			(stroke
				(width 0.1)
				(type default)
			)
			(layer "F.Fab")
		)
		(fp_line
			(start 0.12065 -0.3048)
			(end 0.67945 -0.3048)
			(stroke
				(width 0.1)
				(type default)
			)
			(layer "F.Fab")
		)
		(fp_line
			(start 0.12065 -0.2794)
			(end 0.12065 -0.3048)
			(stroke
				(width 0.1)
				(type default)
			)
			(layer "F.Fab")
		)
		(fp_line
			(start 0.67945 -0.3048)
			(end 0.67945 0.3048)
			(stroke
				(width 0.1)
				(type default)
			)
			(layer "F.Fab")
		)
		(fp_line
			(start 0.67945 0.3048)
			(end 0.120396 0.3048)
			(stroke
				(width 0.1)
				(type default)
			)
			(layer "F.Fab")
		)
		(pad "1" smd circle
			(at -0.40005 0)
			(size 0 0)
			(layers "F.Cu" "F.Mask" "F.Paste")
			(net "GPU_3V3IO_RSVD3_ISO_R")
		)
		(pad "2" smd circle
			(at 0.40005 0)
			(size 0 0)
			(layers "F.Cu" "F.Mask" "F.Paste")
			(net "GPU_3V3IO_RSVD3_ISO")
		)
	)
)
